(kicad_pcb
	(version 20260206)
	(generator "pcbnew")
	(generator_version "10.0")
	(general
		(thickness 1.6)
		(legacy_teardrops no)
	)
	(paper "A4")
	(title_block
		(title "12092022_DA0F0TMDCD0_F0T_Management_Board_D_brd_V3_OCP.brd")
		(comment 1 "Grand Teton / footprint 162 of 1440 (U25), pads 113-228 of 256")
	)
	(layers
		(0 "F.Cu" signal "TOP")
		(4 "In1.Cu" signal "GND")
		(6 "In2.Cu" signal "IN1")
		(8 "In3.Cu" signal "GND1")
		(10 "In4.Cu" signal "IN2")
		(12 "In5.Cu" signal "VCC")
		(14 "In6.Cu" signal "VCC1")
		(16 "In7.Cu" signal "IN3")
		(18 "In8.Cu" signal "GND2")
		(20 "In9.Cu" signal "IN4")
		(22 "In10.Cu" signal "GND3")
		(2 "B.Cu" signal "BOTTOM")
		(9 "F.Adhes" user "F.Adhesive")
		(11 "B.Adhes" user "B.Adhesive")
		(13 "F.Paste" user "Package Geometry/Pastemask Top")
		(15 "B.Paste" user "Package Geometry/Pastemask Bottom")
		(5 "F.SilkS" user "Ref Des/Silkscreen Top")
		(7 "B.SilkS" user "Ref Des/Silkscreen Bottom")
		(1 "F.Mask" user "Board Geometry/Soldermask Top")
		(3 "B.Mask" user "Board Geometry/Soldermask Bottom")
		(17 "Dwgs.User" user "User.Drawings")
		(19 "Cmts.User" user "User.Comments")
		(21 "Eco1.User" user "User.Eco1")
		(23 "Eco2.User" user "User.Eco2")
		(25 "Edge.Cuts" user "Board Geometry/Outline")
		(27 "Margin" user)
		(31 "F.CrtYd" user "Package Geometry/Place Bound Top")
		(29 "B.CrtYd" user "Package Geometry/Place Bound Bottom")
		(35 "F.Fab" user "Ref Des/Assembly Top")
		(33 "B.Fab" user "Ref Des/Assembly Bottom")
	)
	(footprint ""
		(layer "F.Cu")
		(at 21.459444 -93.587062 180)
		(property "Reference" "U25"
			(at -10.595356 -8.218932 0)
			(unlocked yes)
			(layer "F.SilkS")
			(effects
				(font
					(size 0.7874 0.5842)
					(thickness 0.1524)
				)
				(justify left)
			)
		)
		(property "Value" ""
			(at 0 0 180)
			(layer "F.Fab")
			(effects
				(font
					(size 1.27 1.27)
				)
			)
		)
		(duplicate_pad_numbers_are_jumpers no)
		(pad "H1" smd circle
			(at -5.999988 -0.40005 180)
			(size 0.4064 0.4064)
			(layers "F.Cu" "F.Mask" "F.Paste")
			(net "Net_289")
		)
		(pad "H2" smd circle
			(at -5.199888 -0.40005 180)
			(size 0.4064 0.4064)
			(layers "F.Cu" "F.Mask" "F.Paste")
			(net "Net_285")
		)
		(pad "H3" smd circle
			(at -4.400042 -0.40005 180)
			(size 0.4064 0.4064)
			(layers "F.Cu" "F.Mask" "F.Paste")
			(net "Net_288")
		)
		(pad "H4" smd circle
			(at -3.599942 -0.40005 180)
			(size 0.4064 0.4064)
			(layers "F.Cu" "F.Mask" "F.Paste")
			(net "Net_286")
		)
		(pad "H5" smd circle
			(at -2.800096 -0.40005 180)
			(size 0.4064 0.4064)
			(layers "F.Cu" "F.Mask" "F.Paste")
			(net "Net_294")
		)
		(pad "H6" smd circle
			(at -1.999996 -0.40005 180)
			(size 0.4064 0.4064)
			(layers "F.Cu" "F.Mask" "F.Paste")
			(net "Net_315")
		)
		(pad "H7" smd circle
			(at -1.199896 -0.40005 180)
			(size 0.4064 0.4064)
			(layers "F.Cu" "F.Mask" "F.Paste")
			(net "VCCIO4")
		)
		(pad "H8" smd circle
			(at -0.40005 -0.40005 180)
			(size 0.4064 0.4064)
			(layers "F.Cu" "F.Mask" "F.Paste")
			(net "GND")
		)
		(pad "H9" smd circle
			(at 0.40005 -0.40005 180)
			(size 0.4064 0.4064)
			(layers "F.Cu" "F.Mask" "F.Paste")
			(net "GND")
		)
		(pad "H10" smd circle
			(at 1.199896 -0.40005 180)
			(size 0.4064 0.4064)
			(layers "F.Cu" "F.Mask" "F.Paste")
			(net "VCCIO1")
		)
		(pad "H11" smd circle
			(at 1.999996 -0.40005 180)
			(size 0.4064 0.4064)
			(layers "F.Cu" "F.Mask" "F.Paste")
			(net "RST_MB_STBY_R_N")
		)
		(pad "H12" smd circle
			(at 2.800096 -0.40005 180)
			(size 0.4064 0.4064)
			(layers "F.Cu" "F.Mask" "F.Paste")
			(net "RST_ROT_CPU_R_N")
		)
		(pad "H13" smd circle
			(at 3.599942 -0.40005 180)
			(size 0.4064 0.4064)
			(layers "F.Cu" "F.Mask" "F.Paste")
			(net "FM_ESPI_PLD_R_EN")
		)
		(pad "H14" smd circle
			(at 4.400042 -0.40005 180)
			(size 0.4064 0.4064)
			(layers "F.Cu" "F.Mask" "F.Paste")
			(net "Net_71")
		)
		(pad "H15" smd circle
			(at 5.199888 -0.40005 180)
			(size 0.4064 0.4064)
			(layers "F.Cu" "F.Mask" "F.Paste")
			(net "BMC_CPLD_GPIO_13_R2")
		)
		(pad "H16" smd circle
			(at 5.999988 -0.40005 180)
			(size 0.4064 0.4064)
			(layers "F.Cu" "F.Mask" "F.Paste")
			(net "Net_72")
		)
		(pad "J1" smd circle
			(at -5.999988 0.40005 180)
			(size 0.4064 0.4064)
			(layers "F.Cu" "F.Mask" "F.Paste")
			(net "Net_290")
		)
		(pad "J2" smd circle
			(at -5.199888 0.40005 180)
			(size 0.4064 0.4064)
			(layers "F.Cu" "F.Mask" "F.Paste")
			(net "Net_292")
		)
		(pad "J3" smd circle
			(at -4.400042 0.40005 180)
			(size 0.4064 0.4064)
			(layers "F.Cu" "F.Mask" "F.Paste")
			(net "Net_291")
		)
		(pad "J4" smd circle
			(at -3.599942 0.40005 180)
			(size 0.4064 0.4064)
			(layers "F.Cu" "F.Mask" "F.Paste")
			(net "Net_295")
		)
		(pad "J5" smd circle
			(at -2.800096 0.40005 180)
			(size 0.4064 0.4064)
			(layers "F.Cu" "F.Mask" "F.Paste")
			(net "Net_282")
		)
		(pad "J6" smd circle
			(at -1.999996 0.40005 180)
			(size 0.4064 0.4064)
			(layers "F.Cu" "F.Mask" "F.Paste")
			(net "Net_287")
		)
		(pad "J7" smd circle
			(at -1.199896 0.40005 180)
			(size 0.4064 0.4064)
			(layers "F.Cu" "F.Mask" "F.Paste")
			(net "VCCIO4")
		)
		(pad "J8" smd circle
			(at -0.40005 0.40005 180)
			(size 0.4064 0.4064)
			(layers "F.Cu" "F.Mask" "F.Paste")
			(net "GND")
		)
		(pad "J9" smd circle
			(at 0.40005 0.40005 180)
			(size 0.4064 0.4064)
			(layers "F.Cu" "F.Mask" "F.Paste")
			(net "GND")
		)
		(pad "J10" smd circle
			(at 1.199896 0.40005 180)
			(size 0.4064 0.4064)
			(layers "F.Cu" "F.Mask" "F.Paste")
			(net "VCCIO1")
		)
		(pad "J11" smd circle
			(at 1.999996 0.40005 180)
			(size 0.4064 0.4064)
			(layers "F.Cu" "F.Mask" "F.Paste")
			(net "Net_37")
		)
		(pad "J12" smd circle
			(at 2.800096 0.40005 180)
			(size 0.4064 0.4064)
			(layers "F.Cu" "F.Mask" "F.Paste")
			(net "FM_THROTTLE_R_N")
		)
		(pad "J13" smd circle
			(at 3.599942 0.40005 180)
			(size 0.4064 0.4064)
			(layers "F.Cu" "F.Mask" "F.Paste")
			(net "FM_ADR_TRIGGER_N")
		)
		(pad "J14" smd circle
			(at 4.400042 0.40005 180)
			(size 0.4064 0.4064)
			(layers "F.Cu" "F.Mask" "F.Paste")
			(net "H_CPU0_PROCHOT_LVC1_R_N")
		)
		(pad "J15" smd circle
			(at 5.199888 0.40005 180)
			(size 0.4064 0.4064)
			(layers "F.Cu" "F.Mask" "F.Paste")
			(net "RST_BMC_HW_R")
		)
		(pad "J16" smd circle
			(at 5.999988 0.40005 180)
			(size 0.4064 0.4064)
			(layers "F.Cu" "F.Mask" "F.Paste")
			(net "FM_PMBUS_ALERT_EN")
		)
		(pad "K1" smd circle
			(at -5.999988 1.199896 180)
			(size 0.4064 0.4064)
			(layers "F.Cu" "F.Mask" "F.Paste")
			(net "Net_293")
		)
		(pad "K2" smd circle
			(at -5.199888 1.199896 180)
			(size 0.4064 0.4064)
			(layers "F.Cu" "F.Mask" "F.Paste")
			(net "Net_281")
		)
		(pad "K3" smd circle
			(at -4.400042 1.199896 180)
			(size 0.4064 0.4064)
			(layers "F.Cu" "F.Mask" "F.Paste")
			(net "Net_280")
		)
		(pad "K4" smd circle
			(at -3.599942 1.199896 180)
			(size 0.4064 0.4064)
			(layers "F.Cu" "F.Mask" "F.Paste")
			(net "Net_266")
		)
		(pad "K5" smd circle
			(at -2.800096 1.199896 180)
			(size 0.4064 0.4064)
			(layers "F.Cu" "F.Mask" "F.Paste")
			(net "Net_270")
		)
		(pad "K6" smd circle
			(at -1.999996 1.199896 180)
			(size 0.4064 0.4064)
			(layers "F.Cu" "F.Mask" "F.Paste")
			(net "Net_283")
		)
		(pad "K7" smd circle
			(at -1.199896 1.199896 180)
			(size 0.4064 0.4064)
			(layers "F.Cu" "F.Mask" "F.Paste")
			(net "PVCCA_AUX_PLD")
		)
		(pad "K8" smd circle
			(at -0.40005 1.199896 180)
			(size 0.4064 0.4064)
			(layers "F.Cu" "F.Mask" "F.Paste")
			(net "VCCIO2")
		)
		(pad "K9" smd circle
			(at 0.40005 1.199896 180)
			(size 0.4064 0.4064)
			(layers "F.Cu" "F.Mask" "F.Paste")
			(net "VCCIO2")
		)
		(pad "K10" smd circle
			(at 1.199896 1.199896 180)
			(size 0.4064 0.4064)
			(layers "F.Cu" "F.Mask" "F.Paste")
			(net "PVCCA_AUX_PLD")
		)
		(pad "K11" smd circle
			(at 1.999996 1.199896 180)
			(size 0.4064 0.4064)
			(layers "F.Cu" "F.Mask" "F.Paste")
			(net "FM_PCHHOT_R_N")
		)
		(pad "K12" smd circle
			(at 2.800096 1.199896 180)
			(size 0.4064 0.4064)
			(layers "F.Cu" "F.Mask" "F.Paste")
			(net "FM_BIOS_DEBUG_EN_N")
		)
		(pad "K13" smd circle
			(at 3.599942 1.199896 180)
			(size 0.4064 0.4064)
			(layers "F.Cu" "F.Mask" "F.Paste")
			(net "FM_BMC_READY_PLD_N")
		)
		(pad "K14" smd circle
			(at 4.400042 1.199896 180)
			(size 0.4064 0.4064)
			(layers "F.Cu" "F.Mask" "F.Paste")
			(net "FM_PWR_R_BTN")
		)
		(pad "K15" smd circle
			(at 5.199888 1.199896 180)
			(size 0.4064 0.4064)
			(layers "F.Cu" "F.Mask" "F.Paste")
			(net "PWRGD_SYS_PWROK_PLD")
		)
		(pad "K16" smd circle
			(at 5.999988 1.199896 180)
			(size 0.4064 0.4064)
			(layers "F.Cu" "F.Mask" "F.Paste")
			(net "Net_247")
		)
		(pad "L1" smd circle
			(at -5.999988 1.999996 180)
			(size 0.4064 0.4064)
			(layers "F.Cu" "F.Mask" "F.Paste")
			(net "Net_264")
		)
		(pad "L2" smd circle
			(at -5.199888 1.999996 180)
			(size 0.4064 0.4064)
			(layers "F.Cu" "F.Mask" "F.Paste")
			(net "Net_268")
		)
		(pad "L3" smd circle
			(at -4.400042 1.999996 180)
			(size 0.4064 0.4064)
			(layers "F.Cu" "F.Mask" "F.Paste")
			(net "Net_265")
		)
		(pad "L4" smd circle
			(at -3.599942 1.999996 180)
			(size 0.4064 0.4064)
			(layers "F.Cu" "F.Mask" "F.Paste")
			(net "Net_271")
		)
		(pad "L5" smd circle
			(at -2.800096 1.999996 180)
			(size 0.4064 0.4064)
			(layers "F.Cu" "F.Mask" "F.Paste")
			(net "Net_267")
		)
		(pad "L6" smd circle
			(at -1.999996 1.999996 180)
			(size 0.4064 0.4064)
			(layers "F.Cu" "F.Mask" "F.Paste")
			(net "GND")
		)
		(pad "L7" smd circle
			(at -1.199896 1.999996 180)
			(size 0.4064 0.4064)
			(layers "F.Cu" "F.Mask" "F.Paste")
			(net "NC_FM_PFR_NO_SERVICE_ACT_N")
		)
		(pad "L8" smd circle
			(at -0.40005 1.999996 180)
			(size 0.4064 0.4064)
			(layers "F.Cu" "F.Mask" "F.Paste")
			(net "FM_PFR_DSW_PWROK_N")
		)
		(pad "L9" smd circle
			(at 0.40005 1.999996 180)
			(size 0.4064 0.4064)
			(layers "F.Cu" "F.Mask" "F.Paste")
			(net "FM_BMC_CPU_FBRK_OUT_R_N")
		)
		(pad "L10" smd circle
			(at 1.199896 1.999996 180)
			(size 0.4064 0.4064)
			(layers "F.Cu" "F.Mask" "F.Paste")
			(net "FM_UARTSW_MSB_R_N")
		)
		(pad "L11" smd circle
			(at 1.999996 1.999996 180)
			(size 0.4064 0.4064)
			(layers "F.Cu" "F.Mask" "F.Paste")
			(net "GND")
		)
		(pad "L12" smd circle
			(at 2.800096 1.999996 180)
			(size 0.4064 0.4064)
			(layers "F.Cu" "F.Mask" "F.Paste")
			(net "FM_BMC_EN_DET_R")
		)
		(pad "L13" smd circle
			(at 3.599942 1.999996 180)
			(size 0.4064 0.4064)
			(layers "F.Cu" "F.Mask" "F.Paste")
			(net "FM_BMC_ONCTL_R_N")
		)
		(pad "L14" smd circle
			(at 4.400042 1.999996 180)
			(size 0.4064 0.4064)
			(layers "F.Cu" "F.Mask" "F.Paste")
			(net "SMB_BMC_ALERT12_N")
		)
		(pad "L15" smd circle
			(at 5.199888 1.999996 180)
			(size 0.4064 0.4064)
			(layers "F.Cu" "F.Mask" "F.Paste")
			(net "Net_78")
		)
		(pad "L16" smd circle
			(at 5.999988 1.999996 180)
			(size 0.4064 0.4064)
			(layers "F.Cu" "F.Mask" "F.Paste")
			(net "USB_OC0_REAR_R_N")
		)
		(pad "M1" smd circle
			(at -5.999988 2.800096 180)
			(size 0.4064 0.4064)
			(layers "F.Cu" "F.Mask" "F.Paste")
			(net "Net_269")
		)
		(pad "M2" smd circle
			(at -5.199888 2.800096 180)
			(size 0.4064 0.4064)
			(layers "F.Cu" "F.Mask" "F.Paste")
			(net "Net_276")
		)
		(pad "M3" smd circle
			(at -4.400042 2.800096 180)
			(size 0.4064 0.4064)
			(layers "F.Cu" "F.Mask" "F.Paste")
			(net "Net_272")
		)
		(pad "M4" smd circle
			(at -3.599942 2.800096 180)
			(size 0.4064 0.4064)
			(layers "F.Cu" "F.Mask" "F.Paste")
			(net "VCCIO3")
		)
		(pad "M5" smd circle
			(at -2.800096 2.800096 180)
			(size 0.4064 0.4064)
			(layers "F.Cu" "F.Mask" "F.Paste")
			(net "GND")
		)
		(pad "M6" smd circle
			(at -1.999996 2.800096 180)
			(size 0.4064 0.4064)
			(layers "F.Cu" "F.Mask" "F.Paste")
			(net "BMC_MONITER")
		)
		(pad "M7" smd circle
			(at -1.199896 2.800096 180)
			(size 0.4064 0.4064)
			(layers "F.Cu" "F.Mask" "F.Paste")
			(net "CLK_GEN2_BMC_RC_OE_N")
		)
		(pad "M8" smd circle
			(at -0.40005 2.800096 180)
			(size 0.4064 0.4064)
			(layers "F.Cu" "F.Mask" "F.Paste")
			(net "PWRGD_P1V8_AUX_R1")
		)
		(pad "M9" smd circle
			(at 0.40005 2.800096 180)
			(size 0.4064 0.4064)
			(layers "F.Cu" "F.Mask" "F.Paste")
			(net "FM_UARTSW_LSB_R_N")
		)
		(pad "M10" smd circle
			(at 1.199896 2.800096 180)
			(size 0.4064 0.4064)
			(layers "F.Cu" "F.Mask" "F.Paste")
			(net "PU_FPGA_NCONFIG")
		)
		(pad "M11" smd circle
			(at 1.999996 2.800096 180)
			(size 0.4064 0.4064)
			(layers "F.Cu" "F.Mask" "F.Paste")
			(net "Net_253")
		)
		(pad "M12" smd circle
			(at 2.800096 2.800096 180)
			(size 0.4064 0.4064)
			(layers "F.Cu" "F.Mask" "F.Paste")
			(net "GND")
		)
		(pad "M13" smd circle
			(at 3.599942 2.800096 180)
			(size 0.4064 0.4064)
			(layers "F.Cu" "F.Mask" "F.Paste")
			(net "VCCIO1")
		)
		(pad "M14" smd circle
			(at 4.400042 2.800096 180)
			(size 0.4064 0.4064)
			(layers "F.Cu" "F.Mask" "F.Paste")
			(net "PWR_LED_CPLD")
		)
		(pad "M15" smd circle
			(at 5.199888 2.800096 180)
			(size 0.4064 0.4064)
			(layers "F.Cu" "F.Mask" "F.Paste")
			(net "PWRGD_P5V_AUX_R1")
		)
		(pad "M16" smd circle
			(at 5.999988 2.800096 180)
			(size 0.4064 0.4064)
			(layers "F.Cu" "F.Mask" "F.Paste")
			(net "Net_79")
		)
		(pad "N1" smd circle
			(at -5.999988 3.599942 180)
			(size 0.4064 0.4064)
			(layers "F.Cu" "F.Mask" "F.Paste")
			(net "Net_273")
		)
		(pad "N2" smd circle
			(at -5.199888 3.599942 180)
			(size 0.4064 0.4064)
			(layers "F.Cu" "F.Mask" "F.Paste")
			(net "Net_274")
		)
		(pad "N3" smd circle
			(at -4.400042 3.599942 180)
			(size 0.4064 0.4064)
			(layers "F.Cu" "F.Mask" "F.Paste")
			(net "Net_277")
		)
		(pad "N4" smd circle
			(at -3.599942 3.599942 180)
			(size 0.4064 0.4064)
			(layers "F.Cu" "F.Mask" "F.Paste")
			(net "GND")
		)
		(pad "N5" smd circle
			(at -2.800096 3.599942 180)
			(size 0.4064 0.4064)
			(layers "F.Cu" "F.Mask" "F.Paste")
			(net "VCCIO2")
		)
		(pad "N6" smd circle
			(at -1.999996 3.599942 180)
			(size 0.4064 0.4064)
			(layers "F.Cu" "F.Mask" "F.Paste")
			(net "FM_BMC_DEBUG_SW_R2_N")
		)
		(pad "N7" smd circle
			(at -1.199896 3.599942 180)
			(size 0.4064 0.4064)
			(layers "F.Cu" "F.Mask" "F.Paste")
			(net "IRQ_SML0_ALERT_R_N")
		)
		(pad "N8" smd circle
			(at -0.40005 3.599942 180)
			(size 0.4064 0.4064)
			(layers "F.Cu" "F.Mask" "F.Paste")
			(net "CLK_BUF1_GPU_FPGA_OE_R_N")
		)
		(pad "N9" smd circle
			(at 0.40005 3.599942 180)
			(size 0.4064 0.4064)
			(layers "F.Cu" "F.Mask" "F.Paste")
			(net "PWRGD_P3V3_RGM_R1")
		)
		(pad "N10" smd circle
			(at 1.199896 3.599942 180)
			(size 0.4064 0.4064)
			(layers "F.Cu" "F.Mask" "F.Paste")
			(net "Net_252")
		)
		(pad "N11" smd circle
			(at 1.999996 3.599942 180)
			(size 0.4064 0.4064)
			(layers "F.Cu" "F.Mask" "F.Paste")
			(net "Net_256")
		)
		(pad "N12" smd circle
			(at 2.800096 3.599942 180)
			(size 0.4064 0.4064)
			(layers "F.Cu" "F.Mask" "F.Paste")
			(net "VCCIO2")
		)
		(pad "N13" smd circle
			(at 3.599942 3.599942 180)
			(size 0.4064 0.4064)
			(layers "F.Cu" "F.Mask" "F.Paste")
			(net "GND")
		)
		(pad "N14" smd circle
			(at 4.400042 3.599942 180)
			(size 0.4064 0.4064)
			(layers "F.Cu" "F.Mask" "F.Paste")
			(net "PWRGD_P2V5_AUX_R1")
		)
		(pad "N15" smd circle
			(at 5.199888 3.599942 180)
			(size 0.4064 0.4064)
			(layers "F.Cu" "F.Mask" "F.Paste")
			(net "AC_PWR_BTN_R2_N")
		)
		(pad "N16" smd circle
			(at 5.999988 3.599942 180)
			(size 0.4064 0.4064)
			(layers "F.Cu" "F.Mask" "F.Paste")
			(net "PWRGD_P3V3_AUX_R1")
		)
		(pad "P1" smd circle
			(at -5.999988 4.400042 180)
			(size 0.4064 0.4064)
			(layers "F.Cu" "F.Mask" "F.Paste")
			(net "Net_275")
		)
		(pad "P2" smd circle
			(at -5.199888 4.400042 180)
			(size 0.4064 0.4064)
			(layers "F.Cu" "F.Mask" "F.Paste")
			(net "Net_279")
		)
		(pad "P3" smd circle
			(at -4.400042 4.400042 180)
			(size 0.4064 0.4064)
			(layers "F.Cu" "F.Mask" "F.Paste")
			(net "GND")
		)
		(pad "P4" smd circle
			(at -3.599942 4.400042 180)
			(size 0.4064 0.4064)
			(layers "F.Cu" "F.Mask" "F.Paste")
			(net "FM_P12V_HSC_ENABLE_R2")
		)
		(pad "P5" smd circle
			(at -2.800096 4.400042 180)
			(size 0.4064 0.4064)
			(layers "F.Cu" "F.Mask" "F.Paste")
			(net "TP_PLD_C13")
		)
		(pad "P6" smd circle
			(at -1.999996 4.400042 180)
			(size 0.4064 0.4064)
			(layers "F.Cu" "F.Mask" "F.Paste")
			(net "FM_HDD_LED_N")
		)
		(pad "P7" smd circle
			(at -1.199896 4.400042 180)
			(size 0.4064 0.4064)
			(layers "F.Cu" "F.Mask" "F.Paste")
			(net "GPU_WP_HW_CTRL_R_N")
		)
		(pad "P8" smd circle
			(at -0.40005 4.400042 180)
			(size 0.4064 0.4064)
			(layers "F.Cu" "F.Mask" "F.Paste")
			(net "GPU_FPGA_RST_N")
		)
		(pad "P9" smd circle
			(at 0.40005 4.400042 180)
			(size 0.4064 0.4064)
			(layers "F.Cu" "F.Mask" "F.Paste")
			(net "PWRGD_P1V0_AUX_R1")
		)
		(pad "P10" smd circle
			(at 1.199896 4.400042 180)
			(size 0.4064 0.4064)
			(layers "F.Cu" "F.Mask" "F.Paste")
			(net "Net_250")
		)
		(pad "P11" smd circle
			(at 1.999996 4.400042 180)
			(size 0.4064 0.4064)
			(layers "F.Cu" "F.Mask" "F.Paste")
			(net "Net_255")
		)
		(pad "P12" smd circle
			(at 2.800096 4.400042 180)
			(size 0.4064 0.4064)
			(layers "F.Cu" "F.Mask" "F.Paste")
			(net "Net_261")
		)
		(pad "P13" smd circle
			(at 3.599942 4.400042 180)
			(size 0.4064 0.4064)
			(layers "F.Cu" "F.Mask" "F.Paste")
			(net "Net_263")
		)
		(pad "P14" smd circle
			(at 4.400042 4.400042 180)
			(size 0.4064 0.4064)
			(layers "F.Cu" "F.Mask" "F.Paste")
			(net "GND")
		)
		(pad "P15" smd circle
			(at 5.199888 4.400042 180)
			(size 0.4064 0.4064)
			(layers "F.Cu" "F.Mask" "F.Paste")
			(net "Net_74")
		)
		(pad "P16" smd circle
			(at 5.999988 4.400042 180)
			(size 0.4064 0.4064)
			(layers "F.Cu" "F.Mask" "F.Paste")
			(net "Net_73")
		)
		(pad "R1" smd circle
			(at -5.999988 5.199888 180)
			(size 0.4064 0.4064)
			(layers "F.Cu" "F.Mask" "F.Paste")
			(net "Net_278")
		)
		(pad "R2" smd circle
			(at -5.199888 5.199888 180)
			(size 0.4064 0.4064)
			(layers "F.Cu" "F.Mask" "F.Paste")
			(net "GND")
		)
		(pad "R3" smd circle
			(at -4.400042 5.199888 180)
			(size 0.4064 0.4064)
			(layers "F.Cu" "F.Mask" "F.Paste")
			(net "PWRGD_DSW_PWROK_R2")
		)
		(pad "R4" smd circle
			(at -3.599942 5.199888 180)
			(size 0.4064 0.4064)
			(layers "F.Cu" "F.Mask" "F.Paste")
			(net "FM_BMC_SUSACK_R2_N")
		)
	)
)
